(kicad_pcb
	(version 20260206)
	(generator "pcbnew")
	(generator_version "10.0")
	(general
		(thickness 1.6)
		(legacy_teardrops no)
	)
	(paper "A4")
	(title_block
		(title "12092022_DA0F0TMDCD0_F0T_Management_Board_D_brd_V3_OCP.brd")
		(comment 1 "Grand Teton / footprints 219-224 of 1440")
	)
	(layers
		(0 "F.Cu" signal "TOP")
		(4 "In1.Cu" signal "GND")
		(6 "In2.Cu" signal "IN1")
		(8 "In3.Cu" signal "GND1")
		(10 "In4.Cu" signal "IN2")
		(12 "In5.Cu" signal "VCC")
		(14 "In6.Cu" signal "VCC1")
		(16 "In7.Cu" signal "IN3")
		(18 "In8.Cu" signal "GND2")
		(20 "In9.Cu" signal "IN4")
		(22 "In10.Cu" signal "GND3")
		(2 "B.Cu" signal "BOTTOM")
		(9 "F.Adhes" user "F.Adhesive")
		(11 "B.Adhes" user "B.Adhesive")
		(13 "F.Paste" user "Package Geometry/Pastemask Top")
		(15 "B.Paste" user "Package Geometry/Pastemask Bottom")
		(5 "F.SilkS" user "Ref Des/Silkscreen Top")
		(7 "B.SilkS" user "Ref Des/Silkscreen Bottom")
		(1 "F.Mask" user "Board Geometry/Soldermask Top")
		(3 "B.Mask" user "Board Geometry/Soldermask Bottom")
		(17 "Dwgs.User" user "User.Drawings")
		(19 "Cmts.User" user "User.Comments")
		(21 "Eco1.User" user "User.Eco1")
		(23 "Eco2.User" user "User.Eco2")
		(25 "Edge.Cuts" user "Board Geometry/Outline")
		(27 "Margin" user)
		(31 "F.CrtYd" user "Package Geometry/Place Bound Top")
		(29 "B.CrtYd" user "Package Geometry/Place Bound Bottom")
		(35 "F.Fab" user "Ref Des/Assembly Top")
		(33 "B.Fab" user "Ref Des/Assembly Bottom")
	)
	(footprint ""
		(layer "F.Cu")
		(at 81.6102 -17.907 180)
		(property "Reference" "U32"
			(at 2.101088 1.814322 0)
			(unlocked yes)
			(layer "F.SilkS")
			(effects
				(font
					(size 0.7874 0.5842)
					(thickness 0.1524)
				)
				(justify left)
			)
		)
		(property "Value" ""
			(at 0 0 180)
			(layer "F.Fab")
			(effects
				(font
					(size 1.27 1.27)
				)
			)
		)
		(duplicate_pad_numbers_are_jumpers no)
		(fp_line
			(start 1.695958 1.124966)
			(end -1.695958 1.124966)
			(stroke
				(width 0.1524)
				(type default)
			)
			(layer "F.SilkS")
		)
		(fp_line
			(start 1.695958 -1.124966)
			(end 1.695958 1.124966)
			(stroke
				(width 0.1524)
				(type default)
			)
			(layer "F.SilkS")
		)
		(fp_line
			(start -1.695958 1.124966)
			(end -1.695958 -1.124966)
			(stroke
				(width 0.1524)
				(type default)
			)
			(layer "F.SilkS")
		)
		(fp_line
			(start -1.695958 -1.124966)
			(end 1.695958 -1.124966)
			(stroke
				(width 0.1524)
				(type default)
			)
			(layer "F.SilkS")
		)
		(fp_poly
			(pts
				(xy -0.359918 -2.054352) (xy -0.712216 -1.457452) (xy -0.978154 -2.097278)
			)
			(stroke
				(width 0)
				(type default)
			)
			(fill yes)
			(layer "F.SilkS")
		)
		(fp_line
			(start 0.674878 1.124966)
			(end -0.674878 1.124966)
			(stroke
				(width 0.1)
				(type default)
			)
			(layer "F.Fab")
		)
		(fp_line
			(start 0.674878 -1.124966)
			(end 0.674878 1.124966)
			(stroke
				(width 0.1)
				(type default)
			)
			(layer "F.Fab")
		)
		(fp_line
			(start -0.674878 1.124966)
			(end -0.674878 -1.124966)
			(stroke
				(width 0.1)
				(type default)
			)
			(layer "F.Fab")
		)
		(fp_line
			(start -0.674878 -1.124966)
			(end 0.674878 -1.124966)
			(stroke
				(width 0.1)
				(type default)
			)
			(layer "F.Fab")
		)
		(fp_poly
			(pts
				(xy -2.4892 -0.959866) (xy -1.86944 -0.649986) (xy -2.4892 -0.340106)
			)
			(stroke
				(width 0)
				(type default)
			)
			(fill yes)
			(layer "F.Fab")
		)
		(pad "1" smd rect
			(at -0.94488 -0.649986 270)
			(size 0.3556 1.2446)
			(layers "F.Cu" "F.Mask" "F.Paste")
			(net "TP_ID_BUF")
		)
		(pad "2" smd rect
			(at -0.94488 0 270)
			(size 0.3556 1.2446)
			(layers "F.Cu" "F.Mask" "F.Paste")
			(net "REAR_ID_RST_BTN_N")
		)
		(pad "3" smd rect
			(at -0.94488 0.649986 270)
			(size 0.3556 1.2446)
			(layers "F.Cu" "F.Mask" "F.Paste")
			(net "GND")
		)
		(pad "4" smd rect
			(at 0.94488 0.649986 270)
			(size 0.3556 1.2446)
			(layers "F.Cu" "F.Mask" "F.Paste")
			(net "ID_RST_BTN_BMC_N")
		)
		(pad "5" smd rect
			(at 0.94488 -0.649986 270)
			(size 0.3556 1.2446)
			(layers "F.Cu" "F.Mask" "F.Paste")
			(net "P3V3_AUX")
		)
	)
	(footprint ""
		(layer "F.Cu")
		(at 22.373082 -31.361888 90)
		(property "Reference" "PC260"
			(at 0 0 90)
			(layer "F.SilkS")
			(hide yes)
			(effects
				(font
					(size 1.27 1.27)
				)
			)
		)
		(property "Value" ""
			(at 0 0 90)
			(layer "F.Fab")
			(effects
				(font
					(size 1.27 1.27)
				)
			)
		)
		(duplicate_pad_numbers_are_jumpers no)
		(fp_line
			(start 0.7874 -0.4064)
			(end 0.7874 0.4064)
			(stroke
				(width 0.1524)
				(type default)
			)
			(layer "F.SilkS")
		)
		(fp_line
			(start -0.7874 -0.4064)
			(end 0.7874 -0.4064)
			(stroke
				(width 0.1524)
				(type default)
			)
			(layer "F.SilkS")
		)
		(fp_line
			(start 0.7874 0.4064)
			(end -0.7874 0.4064)
			(stroke
				(width 0.1524)
				(type default)
			)
			(layer "F.SilkS")
		)
		(fp_line
			(start -0.7874 0.4064)
			(end -0.7874 -0.4064)
			(stroke
				(width 0.1524)
				(type default)
			)
			(layer "F.SilkS")
		)
		(fp_line
			(start -0.12065 -0.305054)
			(end -0.12065 -0.2794)
			(stroke
				(width 0.1)
				(type default)
			)
			(layer "F.Fab")
		)
		(fp_line
			(start -0.67945 -0.305054)
			(end -0.12065 -0.305054)
			(stroke
				(width 0.1)
				(type default)
			)
			(layer "F.Fab")
		)
		(fp_line
			(start 0.67945 -0.3048)
			(end 0.67945 0.3048)
			(stroke
				(width 0.1)
				(type default)
			)
			(layer "F.Fab")
		)
		(fp_line
			(start 0.12065 -0.3048)
			(end 0.67945 -0.3048)
			(stroke
				(width 0.1)
				(type default)
			)
			(layer "F.Fab")
		)
		(fp_line
			(start 0.12065 -0.2794)
			(end 0.12065 -0.3048)
			(stroke
				(width 0.1)
				(type default)
			)
			(layer "F.Fab")
		)
		(fp_line
			(start -0.12065 -0.2794)
			(end 0.12065 -0.2794)
			(stroke
				(width 0.1)
				(type default)
			)
			(layer "F.Fab")
		)
		(fp_line
			(start 0.120396 0.2794)
			(end -0.12065 0.2794)
			(stroke
				(width 0.1)
				(type default)
			)
			(layer "F.Fab")
		)
		(fp_line
			(start -0.12065 0.2794)
			(end -0.12065 0.3048)
			(stroke
				(width 0.1)
				(type default)
			)
			(layer "F.Fab")
		)
		(fp_line
			(start 0.67945 0.3048)
			(end 0.120396 0.3048)
			(stroke
				(width 0.1)
				(type default)
			)
			(layer "F.Fab")
		)
		(fp_line
			(start 0.120396 0.3048)
			(end 0.120396 0.2794)
			(stroke
				(width 0.1)
				(type default)
			)
			(layer "F.Fab")
		)
		(fp_line
			(start -0.12065 0.3048)
			(end -0.67945 0.3048)
			(stroke
				(width 0.1)
				(type default)
			)
			(layer "F.Fab")
		)
		(fp_line
			(start -0.67945 0.3048)
			(end -0.67945 -0.305054)
			(stroke
				(width 0.1)
				(type default)
			)
			(layer "F.Fab")
		)
		(pad "1" smd circle
			(at -0.40005 0 90)
			(size 0 0)
			(layers "F.Cu" "F.Mask" "F.Paste")
			(net "P1V0_AUX_VCC")
		)
		(pad "2" smd circle
			(at 0.40005 0 90)
			(size 0 0)
			(layers "F.Cu" "F.Mask" "F.Paste")
			(net "GND")
		)
	)
	(footprint ""
		(layer "F.Cu")
		(at 7.239 -59.309 180)
		(property "Reference" "PC219"
			(at 0 0 180)
			(layer "F.SilkS")
			(hide yes)
			(effects
				(font
					(size 1.27 1.27)
				)
			)
		)
		(property "Value" ""
			(at 0 0 180)
			(layer "F.Fab")
			(effects
				(font
					(size 1.27 1.27)
				)
			)
		)
		(duplicate_pad_numbers_are_jumpers no)
		(fp_line
			(start 1.524 0.762)
			(end -1.524 0.762)
			(stroke
				(width 0.1524)
				(type default)
			)
			(layer "F.SilkS")
		)
		(fp_line
			(start 1.524 -0.762)
			(end 1.524 0.762)
			(stroke
				(width 0.1524)
				(type default)
			)
			(layer "F.SilkS")
		)
		(fp_line
			(start -1.524 0.762)
			(end -1.524 -0.762)
			(stroke
				(width 0.1524)
				(type default)
			)
			(layer "F.SilkS")
		)
		(fp_line
			(start -1.524 -0.762)
			(end 1.524 -0.762)
			(stroke
				(width 0.1524)
				(type default)
			)
			(layer "F.SilkS")
		)
		(fp_line
			(start 1.1049 0.724916)
			(end 1.1049 -0.724916)
			(stroke
				(width 0.1)
				(type default)
			)
			(layer "F.Fab")
		)
		(fp_line
			(start 1.1049 -0.724916)
			(end -1.1049 -0.724916)
			(stroke
				(width 0.1)
				(type default)
			)
			(layer "F.Fab")
		)
		(fp_line
			(start -1.1049 0.724916)
			(end 1.1049 0.724916)
			(stroke
				(width 0.1)
				(type default)
			)
			(layer "F.Fab")
		)
		(fp_line
			(start -1.1049 -0.724916)
			(end -1.1049 0.724916)
			(stroke
				(width 0.1)
				(type default)
			)
			(layer "F.Fab")
		)
		(pad "1" smd rect
			(at -0.889 0)
			(size 1.016 1.27)
			(layers "F.Cu" "F.Mask" "F.Paste")
			(net "SW_P3V3_AUX_FLT")
		)
		(pad "2" smd rect
			(at 0.889 0)
			(size 1.016 1.27)
			(layers "F.Cu" "F.Mask" "F.Paste")
			(net "GND")
		)
	)
	(footprint ""
		(layer "F.Cu")
		(at 78.907894 -28.196032 -90)
		(property "Reference" "D0"
			(at 2.237232 -7.427976 90)
			(unlocked yes)
			(layer "F.SilkS")
			(effects
				(font
					(size 0.7874 0.5842)
					(thickness 0.1524)
				)
				(justify left)
			)
		)
		(property "Value" ""
			(at 0 0 270)
			(layer "F.Fab")
			(effects
				(font
					(size 1.27 1.27)
				)
			)
		)
		(duplicate_pad_numbers_are_jumpers no)
		(fp_line
			(start -1.3208 0.5588)
			(end -1.3208 -0.5588)
			(stroke
				(width 0.1524)
				(type default)
			)
			(layer "F.SilkS")
		)
		(fp_line
			(start 1.3208 0.5588)
			(end -1.3208 0.5588)
			(stroke
				(width 0.1524)
				(type default)
			)
			(layer "F.SilkS")
		)
		(fp_line
			(start 1.6256 0.5588)
			(end 1.6256 -0.5588)
			(stroke
				(width 0.1524)
				(type default)
			)
			(layer "F.SilkS")
		)
		(fp_line
			(start 1.778 0.5588)
			(end 1.3208 0.5588)
			(stroke
				(width 0.1524)
				(type default)
			)
			(layer "F.SilkS")
		)
		(fp_line
			(start -1.3208 -0.5588)
			(end 1.3208 -0.5588)
			(stroke
				(width 0.1524)
				(type default)
			)
			(layer "F.SilkS")
		)
		(fp_line
			(start 1.3208 -0.5588)
			(end 1.3208 0.5588)
			(stroke
				(width 0.1524)
				(type default)
			)
			(layer "F.SilkS")
		)
		(fp_line
			(start 1.4732 -0.5588)
			(end 1.4732 0.5588)
			(stroke
				(width 0.1524)
				(type default)
			)
			(layer "F.SilkS")
		)
		(fp_line
			(start 1.778 -0.5588)
			(end 1.778 0.5588)
			(stroke
				(width 0.1524)
				(type default)
			)
			(layer "F.SilkS")
		)
		(fp_line
			(start 1.778 -0.5588)
			(end 1.3208 -0.5588)
			(stroke
				(width 0.1524)
				(type default)
			)
			(layer "F.SilkS")
		)
		(fp_line
			(start -1.235964 0.508)
			(end -1.1684 0.508)
			(stroke
				(width 0.1)
				(type default)
			)
			(layer "F.Fab")
		)
		(fp_line
			(start -1.1684 0.508)
			(end 1.1684 0.508)
			(stroke
				(width 0.1)
				(type default)
			)
			(layer "F.Fab")
		)
		(fp_line
			(start 1.1684 0.508)
			(end 1.236726 0.508)
			(stroke
				(width 0.1)
				(type default)
			)
			(layer "F.Fab")
		)
		(fp_line
			(start 1.236726 0.508)
			(end 1.236726 -0.508)
			(stroke
				(width 0.1)
				(type default)
			)
			(layer "F.Fab")
		)
		(fp_line
			(start -1.235964 -0.508)
			(end -1.235964 0.508)
			(stroke
				(width 0.1)
				(type default)
			)
			(layer "F.Fab")
		)
		(fp_line
			(start -1.1684 -0.508)
			(end -1.235964 -0.508)
			(stroke
				(width 0.1)
				(type default)
			)
			(layer "F.Fab")
		)
		(fp_line
			(start 1.1684 -0.508)
			(end -1.1684 -0.508)
			(stroke
				(width 0.1)
				(type default)
			)
			(layer "F.Fab")
		)
		(fp_line
			(start 1.236726 -0.508)
			(end 1.1684 -0.508)
			(stroke
				(width 0.1)
				(type default)
			)
			(layer "F.Fab")
		)
		(fp_text user "-"
			(at 1.654302 -0.867156 270)
			(unlocked yes)
			(layer "F.SilkS")
			(effects
				(font
					(size 1.905 1.4224)
					(thickness 0.1524)
				)
				(justify left)
			)
		)
		(fp_text user "+"
			(at -0.711454 -0.930402 90)
			(unlocked yes)
			(layer "F.SilkS")
			(effects
				(font
					(size 1.905 1.4224)
					(thickness 0.1524)
				)
				(justify left)
			)
		)
		(fp_text user "+"
			(at -2.5654 -0.24765 270)
			(unlocked yes)
			(layer "F.Fab")
			(effects
				(font
					(size 1.905 1.4224)
					(thickness 0.1524)
				)
				(justify left)
			)
		)
		(fp_text user "-"
			(at 1.524 -0.24765 270)
			(unlocked yes)
			(layer "F.Fab")
			(effects
				(font
					(size 1.905 1.4224)
					(thickness 0.1524)
				)
				(justify left)
			)
		)
		(pad "A" smd rect
			(at -0.750062 0 270)
			(size 0.8128 0.8128)
			(layers "F.Cu" "F.Mask" "F.Paste")
			(net "LED_POSTCODE_0_R")
		)
		(pad "C" smd rect
			(at 0.750062 0 270)
			(size 0.8128 0.8128)
			(layers "F.Cu" "F.Mask" "F.Paste")
			(net "GND")
		)
	)
	(footprint ""
		(layer "F.Cu")
		(at 24.9682 -62.3062 90)
		(property "Reference" "U2"
			(at -3.81 0.89027 90)
			(unlocked yes)
			(layer "F.SilkS")
			(effects
				(font
					(size 0.7874 0.5842)
					(thickness 0.1524)
				)
				(justify left)
			)
		)
		(property "Value" ""
			(at 0 0 90)
			(layer "F.Fab")
			(effects
				(font
					(size 1.27 1.27)
				)
			)
		)
		(duplicate_pad_numbers_are_jumpers no)
		(fp_line
			(start 0.8636 -1.050036)
			(end 0.542036 -1.050036)
			(stroke
				(width 0.1524)
				(type default)
			)
			(layer "F.SilkS")
		)
		(fp_line
			(start 0.542036 -1.050036)
			(end 0 -0.508)
			(stroke
				(width 0.1524)
				(type default)
			)
			(layer "F.SilkS")
		)
		(fp_line
			(start -0.542036 -1.050036)
			(end -0.8636 -1.050036)
			(stroke
				(width 0.1524)
				(type default)
			)
			(layer "F.SilkS")
		)
		(fp_line
			(start -0.8636 -1.050036)
			(end -0.8636 1.050036)
			(stroke
				(width 0.1524)
				(type default)
			)
			(layer "F.SilkS")
		)
		(fp_line
			(start 0 -0.508)
			(end -0.542036 -1.050036)
			(stroke
				(width 0.1524)
				(type default)
			)
			(layer "F.SilkS")
		)
		(fp_line
			(start 0.8636 1.050036)
			(end 0.8636 -1.050036)
			(stroke
				(width 0.1524)
				(type default)
			)
			(layer "F.SilkS")
		)
		(fp_line
			(start -0.8636 1.050036)
			(end 0.8636 1.050036)
			(stroke
				(width 0.1524)
				(type default)
			)
			(layer "F.SilkS")
		)
		(fp_poly
			(pts
				(xy -2.794 -1.258062) (xy -2.794 -0.242062) (xy -1.778 -0.750062)
			)
			(stroke
				(width 0)
				(type default)
			)
			(fill yes)
			(layer "F.SilkS")
		)
		(fp_line
			(start 1.199896 -1.050036)
			(end -1.199896 -1.050036)
			(stroke
				(width 0.1)
				(type default)
			)
			(layer "F.Fab")
		)
		(fp_line
			(start -1.199896 -1.050036)
			(end -1.199896 1.050036)
			(stroke
				(width 0.1)
				(type default)
			)
			(layer "F.Fab")
		)
		(fp_line
			(start 1.199896 1.050036)
			(end 1.199896 -1.050036)
			(stroke
				(width 0.1)
				(type default)
			)
			(layer "F.Fab")
		)
		(fp_line
			(start -1.199896 1.050036)
			(end 1.199896 1.050036)
			(stroke
				(width 0.1)
				(type default)
			)
			(layer "F.Fab")
		)
		(fp_poly
			(pts
				(xy -2.794 -1.258062) (xy -2.794 -0.242062) (xy -1.778 -0.750062)
			)
			(stroke
				(width 0)
				(type default)
			)
			(fill yes)
			(layer "F.Fab")
		)
		(pad "1" smd rect
			(at -1.35001 -0.750062)
			(size 0.2794 0.7112)
			(layers "F.Cu" "F.Mask" "F.Paste")
			(net "UART_BIC_DBG_TX")
		)
		(pad "2" smd rect
			(at -1.35001 -0.249936)
			(size 0.2794 0.7112)
			(layers "F.Cu" "F.Mask" "F.Paste")
			(net "UART_BMC_5_TXD_BUF1_R")
		)
		(pad "3" smd rect
			(at -1.35001 0.249936)
			(size 0.2794 0.7112)
			(layers "F.Cu" "F.Mask" "F.Paste")
			(net "UART_BMC_1_TXD_R")
		)
		(pad "4" smd rect
			(at -1.35001 0.750062)
			(size 0.2794 0.7112)
			(layers "F.Cu" "F.Mask" "F.Paste")
			(net "GND")
		)
		(pad "5" smd rect
			(at 1.35001 0.750062)
			(size 0.2794 0.7112)
			(layers "F.Cu" "F.Mask" "F.Paste")
			(net "FM_UARTSW_LSB_N")
		)
		(pad "6" smd rect
			(at 1.35001 0.249936)
			(size 0.2794 0.7112)
			(layers "F.Cu" "F.Mask" "F.Paste")
			(net "FM_UARTSW_MSB_N")
		)
		(pad "7" smd rect
			(at 1.35001 -0.249936)
			(size 0.2794 0.7112)
			(layers "F.Cu" "F.Mask" "F.Paste")
			(net "SPA_SOUT_SW_BUF")
		)
		(pad "8" smd rect
			(at 1.35001 -0.750062)
			(size 0.2794 0.7112)
			(layers "F.Cu" "F.Mask" "F.Paste")
			(net "P3V3_AUX")
		)
	)
	(footprint ""
		(layer "F.Cu")
		(at 8.849106 -78.183994 90)
		(property "Reference" "PC228"
			(at 0 0 90)
			(layer "F.SilkS")
			(hide yes)
			(effects
				(font
					(size 1.27 1.27)
				)
			)
		)
		(property "Value" ""
			(at 0 0 90)
			(layer "F.Fab")
			(effects
				(font
					(size 1.27 1.27)
				)
			)
		)
		(duplicate_pad_numbers_are_jumpers no)
		(fp_line
			(start 1.651 -0.8382)
			(end 1.651 0.8382)
			(stroke
				(width 0.1524)
				(type default)
			)
			(layer "F.SilkS")
		)
		(fp_line
			(start -1.651 -0.8382)
			(end 1.651 -0.8382)
			(stroke
				(width 0.1524)
				(type default)
			)
			(layer "F.SilkS")
		)
		(fp_line
			(start 1.651 0.8382)
			(end -1.651 0.8382)
			(stroke
				(width 0.1524)
				(type default)
			)
			(layer "F.SilkS")
		)
		(fp_line
			(start 0 0.8382)
			(end 0 -0.8382)
			(stroke
				(width 0.1524)
				(type default)
			)
			(layer "F.SilkS")
		)
		(fp_line
			(start -1.651 0.8382)
			(end -1.651 -0.8382)
			(stroke
				(width 0.1524)
				(type default)
			)
			(layer "F.SilkS")
		)
		(fp_line
			(start 1.55956 -0.7366)
			(end 1.524 -0.7366)
			(stroke
				(width 0.1)
				(type default)
			)
			(layer "F.Fab")
		)
		(fp_line
			(start 1.524 -0.7366)
			(end -1.524 -0.7366)
			(stroke
				(width 0.1)
				(type default)
			)
			(layer "F.Fab")
		)
		(fp_line
			(start -1.524 -0.7366)
			(end -1.55956 -0.7366)
			(stroke
				(width 0.1)
				(type default)
			)
			(layer "F.Fab")
		)
		(fp_line
			(start -1.55956 -0.7366)
			(end -1.55956 0.7366)
			(stroke
				(width 0.1)
				(type default)
			)
			(layer "F.Fab")
		)
		(fp_line
			(start 1.55956 0.7366)
			(end 1.55956 -0.7366)
			(stroke
				(width 0.1)
				(type default)
			)
			(layer "F.Fab")
		)
		(fp_line
			(start 1.524 0.7366)
			(end 1.55956 0.7366)
			(stroke
				(width 0.1)
				(type default)
			)
			(layer "F.Fab")
		)
		(fp_line
			(start -1.524 0.7366)
			(end 1.524 0.7366)
			(stroke
				(width 0.1)
				(type default)
			)
			(layer "F.Fab")
		)
		(fp_line
			(start -1.55956 0.7366)
			(end -1.524 0.7366)
			(stroke
				(width 0.1)
				(type default)
			)
			(layer "F.Fab")
		)
		(pad "1" smd rect
			(at -0.94996 0 270)
			(size 1.1176 1.3716)
			(layers "F.Cu" "F.Mask" "F.Paste")
			(net "P3V3_AUX")
		)
		(pad "2" smd rect
			(at 0.94996 0 270)
			(size 1.1176 1.3716)
			(layers "F.Cu" "F.Mask" "F.Paste")
			(net "GND")
		)
	)
)
